(kicad_pcb
	(version 20260206)
	(generator "pcbnew")
	(generator_version "10.0")
	(general
		(thickness 1.6)
		(legacy_teardrops no)
	)
	(paper "A4")
	(title_block
		(title "Bryce Canyon_R.DPB_16317-1_OCP.brd")
		(comment 1 "Bryce Canyon / footprints 1907-1913 of 2099")
	)
	(layers
		(0 "F.Cu" signal "TOP")
		(4 "In1.Cu" signal "L2GND")
		(6 "In2.Cu" signal "L3")
		(8 "In3.Cu" signal "L4VCC")
		(10 "In4.Cu" signal "L5VCC")
		(12 "In5.Cu" signal "L6")
		(14 "In6.Cu" signal "L7GND")
		(2 "B.Cu" signal "BOTTOM")
		(9 "F.Adhes" user "F.Adhesive")
		(11 "B.Adhes" user "B.Adhesive")
		(13 "F.Paste" user "Package Geometry/Pastemask Top")
		(15 "B.Paste" user "Package Geometry/Pastemask Bottom")
		(5 "F.SilkS" user "Ref Des/Silkscreen Top")
		(7 "B.SilkS" user "Ref Des/Silkscreen Bottom")
		(1 "F.Mask" user "Board Geometry/Soldermask Top")
		(3 "B.Mask" user "Board Geometry/Soldermask Bottom")
		(17 "Dwgs.User" user "User.Drawings")
		(19 "Cmts.User" user "User.Comments")
		(21 "Eco1.User" user "User.Eco1")
		(23 "Eco2.User" user "User.Eco2")
		(25 "Edge.Cuts" user "Board Geometry/Outline")
		(27 "Margin" user)
		(31 "F.CrtYd" user "Package Geometry/Place Bound Top")
		(29 "B.CrtYd" user "Package Geometry/Place Bound Bottom")
		(35 "F.Fab" user "Ref Des/Assembly Top")
		(33 "B.Fab" user "Ref Des/Assembly Bottom")
	)
	(footprint ""
		(layer "F.Cu")
		(at 34.285682 -129.99085 90)
		(property "Reference" "VIA25"
			(at 0 0 90)
			(layer "F.SilkS")
			(hide yes)
			(effects
				(font
					(size 1.27 1.27)
				)
			)
		)
		(property "Value" "100OHM-8L-2D36MM-L18-GP"
			(at 3.8989 0.5715 90)
			(unlocked yes)
			(layer "F.Fab")
			(hide yes)
			(effects
				(font
					(size 1.016 1.016)
					(thickness 0.1524)
				)
			)
		)
		(property "Device Type" "VIA-PCIE-4P-414097"
			(at 3.8989 -0.9525 90)
			(unlocked yes)
			(layer "F.Fab")
			(hide yes)
			(effects
				(font
					(size 1.016 1.016)
					(thickness 0.1524)
				)
			)
		)
		(duplicate_pad_numbers_are_jumpers no)
		(fp_rect
			(start -2.0701 0.4826)
			(end 2.0701 -0.4826)
			(stroke
				(width 0)
				(type default)
			)
			(fill no)
			(layer "F.CrtYd")
		)
		(fp_rect
			(start -2.0701 0.4826)
			(end 2.0701 -0.4826)
			(stroke
				(width 0)
				(type default)
			)
			(fill no)
			(layer "F.Fab")
		)
		(pad "1" thru_hole circle
			(at -1.5875 0 90)
			(size 0.508 0.508)
			(drill 0.254)
			(layers "*.Cu" "*.Mask")
			(remove_unused_layers no)
			(net "GND")
			(clearance 0.2286)
			(thermal_gap 0.2286)
		)
		(pad "2" thru_hole circle
			(at -0.5715 0 90)
			(size 0.508 0.508)
			(drill 0.254)
			(layers "*.Cu" "*.Mask")
			(remove_unused_layers no)
			(net "PHY_SCC_B_TO_DRV_B_12_DP")
			(clearance 0.2286)
			(thermal_gap 0.2286)
		)
		(pad "3" thru_hole circle
			(at 0.5715 0 90)
			(size 0.508 0.508)
			(drill 0.254)
			(layers "*.Cu" "*.Mask")
			(remove_unused_layers no)
			(net "PHY_SCC_B_TO_DRV_B_12_DN")
			(clearance 0.2286)
			(thermal_gap 0.2286)
		)
		(pad "4" thru_hole circle
			(at 1.5875 0 90)
			(size 0.508 0.508)
			(drill 0.254)
			(layers "*.Cu" "*.Mask")
			(remove_unused_layers no)
			(net "GND")
			(clearance 0.2286)
			(thermal_gap 0.2286)
		)
	)
	(footprint ""
		(layer "F.Cu")
		(at 248.30278 -211.690712)
		(property "Reference" "R109"
			(at 0 0 0)
			(layer "F.SilkS")
			(hide yes)
			(effects
				(font
					(size 1.27 1.27)
				)
			)
		)
		(property "Value" "0R2J-2-GP"
			(at 0.064008 -3.993896 0)
			(unlocked yes)
			(layer "F.Fab")
			(hide yes)
			(effects
				(font
					(size 1.016 1.016)
					(thickness 0.1524)
				)
			)
		)
		(property "Device Type" "R402H16"
			(at 0.064008 -5.517896 0)
			(unlocked yes)
			(layer "F.Fab")
			(hide yes)
			(effects
				(font
					(size 1.016 1.016)
					(thickness 0.1524)
				)
			)
		)
		(duplicate_pad_numbers_are_jumpers no)
		(fp_line
			(start -0.508 -0.9398)
			(end -0.508 0.9398)
			(stroke
				(width 0.1524)
				(type default)
			)
			(layer "F.SilkS")
		)
		(fp_line
			(start 0.508 -0.9398)
			(end -0.508 -0.9398)
			(stroke
				(width 0.1524)
				(type default)
			)
			(layer "F.SilkS")
		)
		(fp_rect
			(start -0.508 0.9398)
			(end 0.508 -0.9398)
			(stroke
				(width 0)
				(type default)
			)
			(fill no)
			(layer "F.CrtYd")
		)
		(fp_rect
			(start -0.508 0.9398)
			(end 0.508 -0.9398)
			(stroke
				(width 0)
				(type default)
			)
			(fill no)
			(layer "F.Fab")
		)
		(pad "1" smd custom
			(at 0 -0.4445)
			(size 0.1397 0.1397)
			(layers "F.Cu" "F.Mask" "F.Paste")
			(net "EEPROM_SCL")
			(options
				(clearance outline)
				(anchor circle)
			)
			(primitives
				(gr_poly
					(pts
						(arc
							(start -0.1778 -0.2794)
							(mid -0.249642 -0.249642)
							(end -0.2794 -0.1778)
						)
						(arc
							(start -0.2794 0.1778)
							(mid -0.249642 0.249642)
							(end -0.1778 0.2794)
						)
						(arc
							(start 0.1778 0.2794)
							(mid 0.249642 0.249642)
							(end 0.2794 0.1778)
						)
						(arc
							(start 0.2794 -0.1778)
							(mid 0.249642 -0.249642)
							(end 0.1778 -0.2794)
						)
					)
					(width 0)
					(fill yes)
				)
			)
		)
		(pad "2" smd custom
			(at 0 0.4445)
			(size 0.1397 0.1397)
			(layers "F.Cu" "F.Mask" "F.Paste")
			(net "I2C_DPB_B_SCL_BUF")
			(options
				(clearance outline)
				(anchor circle)
			)
			(primitives
				(gr_poly
					(pts
						(arc
							(start -0.1778 -0.2794)
							(mid -0.249642 -0.249642)
							(end -0.2794 -0.1778)
						)
						(arc
							(start -0.2794 0.1778)
							(mid -0.249642 0.249642)
							(end -0.1778 0.2794)
						)
						(arc
							(start 0.1778 0.2794)
							(mid 0.249642 0.249642)
							(end 0.2794 0.1778)
						)
						(arc
							(start 0.2794 -0.1778)
							(mid 0.249642 -0.249642)
							(end 0.1778 -0.2794)
						)
					)
					(width 0)
					(fill yes)
				)
			)
		)
	)
	(footprint ""
		(layer "F.Cu")
		(at 158.708852 -133.75005 -90)
		(property "Reference" "VIA34"
			(at 0 0 270)
			(layer "F.SilkS")
			(hide yes)
			(effects
				(font
					(size 1.27 1.27)
				)
			)
		)
		(property "Value" "100OHM-8L-2D36MM-L16-GP"
			(at -3.4036 -0.4572 270)
			(unlocked yes)
			(layer "F.Fab")
			(hide yes)
			(effects
				(font
					(size 1.016 1.016)
					(thickness 0.1524)
				)
			)
		)
		(property "Device Type" "VIA-PCIE-4P-427097"
			(at -3.4036 -1.9812 270)
			(unlocked yes)
			(layer "F.Fab")
			(hide yes)
			(effects
				(font
					(size 1.016 1.016)
					(thickness 0.1524)
				)
			)
		)
		(duplicate_pad_numbers_are_jumpers no)
		(fp_rect
			(start -2.1336 0.4826)
			(end 2.1336 -0.4826)
			(stroke
				(width 0)
				(type default)
			)
			(fill no)
			(layer "F.CrtYd")
		)
		(fp_rect
			(start -2.1336 0.4826)
			(end 2.1336 -0.4826)
			(stroke
				(width 0)
				(type default)
			)
			(fill no)
			(layer "F.Fab")
		)
		(pad "1" thru_hole circle
			(at -1.651 0 270)
			(size 0.508 0.508)
			(drill 0.254)
			(layers "*.Cu" "*.Mask")
			(remove_unused_layers no)
			(net "GND")
			(clearance 0.2286)
			(thermal_gap 0.2286)
		)
		(pad "2" thru_hole circle
			(at -0.635 0 270)
			(size 0.508 0.508)
			(drill 0.254)
			(layers "*.Cu" "*.Mask")
			(remove_unused_layers no)
			(net "PHY_DRV_B_TO_SCC_B_16_DP")
			(clearance 0.2286)
			(thermal_gap 0.2286)
		)
		(pad "3" thru_hole circle
			(at 0.635 0 270)
			(size 0.508 0.508)
			(drill 0.254)
			(layers "*.Cu" "*.Mask")
			(remove_unused_layers no)
			(net "PHY_DRV_B_TO_SCC_B_16_DN")
			(clearance 0.2286)
			(thermal_gap 0.2286)
		)
		(pad "4" thru_hole circle
			(at 1.651 0 270)
			(size 0.508 0.508)
			(drill 0.254)
			(layers "*.Cu" "*.Mask")
			(remove_unused_layers no)
			(net "GND")
			(clearance 0.2286)
			(thermal_gap 0.2286)
		)
	)
	(footprint ""
		(layer "F.Cu")
		(at 455.93 -275.336 180)
		(property "Reference" "C166"
			(at 0 0 180)
			(layer "F.SilkS")
			(hide yes)
			(effects
				(font
					(size 1.27 1.27)
				)
			)
		)
		(property "Value" "SC1U25V3KX-GP"
			(at 0 -2.8194 180)
			(unlocked yes)
			(layer "F.Fab")
			(hide yes)
			(effects
				(font
					(size 1.016 1.016)
					(thickness 0.1524)
				)
			)
		)
		(property "Device Type" "C603H36"
			(at 0 -4.3434 180)
			(unlocked yes)
			(layer "F.Fab")
			(hide yes)
			(effects
				(font
					(size 1.016 1.016)
					(thickness 0.1524)
				)
			)
		)
		(duplicate_pad_numbers_are_jumpers no)
		(fp_line
			(start 0.508 0)
			(end -0.508 0)
			(stroke
				(width 0.2032)
				(type default)
			)
			(layer "F.SilkS")
		)
		(fp_rect
			(start -0.5842 1.3335)
			(end 0.5842 -1.3335)
			(stroke
				(width 0)
				(type default)
			)
			(fill no)
			(layer "F.CrtYd")
		)
		(fp_rect
			(start -0.5842 1.3335)
			(end 0.5842 -1.3335)
			(stroke
				(width 0)
				(type default)
			)
			(fill no)
			(layer "F.Fab")
		)
		(pad "1" smd custom
			(at 0 -0.762 180)
			(size 0.2159 0.2159)
			(layers "F.Cu" "F.Mask" "F.Paste")
			(net "P12V_HDD10")
			(options
				(clearance outline)
				(anchor circle)
			)
			(primitives
				(gr_poly
					(pts
						(arc
							(start -0.3302 -0.4318)
							(mid -0.402042 -0.402042)
							(end -0.4318 -0.3302)
						)
						(arc
							(start -0.4318 0.3302)
							(mid -0.402042 0.402042)
							(end -0.3302 0.4318)
						)
						(arc
							(start 0.3302 0.4318)
							(mid 0.402042 0.402042)
							(end 0.4318 0.3302)
						)
						(arc
							(start 0.4318 -0.3302)
							(mid 0.402042 -0.402042)
							(end 0.3302 -0.4318)
						)
					)
					(width 0)
					(fill yes)
				)
			)
		)
		(pad "2" smd custom
			(at 0 0.762 180)
			(size 0.2159 0.2159)
			(layers "F.Cu" "F.Mask" "F.Paste")
			(net "GND")
			(options
				(clearance outline)
				(anchor circle)
			)
			(primitives
				(gr_poly
					(pts
						(arc
							(start -0.3302 -0.4318)
							(mid -0.402042 -0.402042)
							(end -0.4318 -0.3302)
						)
						(arc
							(start -0.4318 0.3302)
							(mid -0.402042 0.402042)
							(end -0.3302 0.4318)
						)
						(arc
							(start 0.3302 0.4318)
							(mid 0.402042 0.402042)
							(end 0.4318 0.3302)
						)
						(arc
							(start 0.4318 -0.3302)
							(mid 0.402042 -0.402042)
							(end 0.3302 -0.4318)
						)
					)
					(width 0)
					(fill yes)
				)
			)
		)
	)
	(footprint ""
		(layer "F.Cu")
		(at 167.7162 -372.872 90)
		(property "Reference" "R998"
			(at 0 0 90)
			(layer "F.SilkS")
			(hide yes)
			(effects
				(font
					(size 1.27 1.27)
				)
			)
		)
		(property "Value" "10R2F-L-GP"
			(at 0.064008 -3.993896 90)
			(unlocked yes)
			(layer "F.Fab")
			(hide yes)
			(effects
				(font
					(size 1.016 1.016)
					(thickness 0.1524)
				)
			)
		)
		(property "Device Type" "R402H14"
			(at 0.064008 -5.517896 90)
			(unlocked yes)
			(layer "F.Fab")
			(hide yes)
			(effects
				(font
					(size 1.016 1.016)
					(thickness 0.1524)
				)
			)
		)
		(duplicate_pad_numbers_are_jumpers no)
		(fp_line
			(start 0.508 -0.9398)
			(end -0.508 -0.9398)
			(stroke
				(width 0.1524)
				(type default)
			)
			(layer "F.SilkS")
		)
		(fp_line
			(start -0.508 -0.9398)
			(end -0.508 0.9398)
			(stroke
				(width 0.1524)
				(type default)
			)
			(layer "F.SilkS")
		)
		(fp_rect
			(start -0.508 0.9398)
			(end 0.508 -0.9398)
			(stroke
				(width 0)
				(type default)
			)
			(fill no)
			(layer "F.CrtYd")
		)
		(fp_rect
			(start -0.508 0.9398)
			(end 0.508 -0.9398)
			(stroke
				(width 0)
				(type default)
			)
			(fill no)
			(layer "F.Fab")
		)
		(pad "1" smd custom
			(at 0 -0.4445 90)
			(size 0.1397 0.1397)
			(layers "F.Cu" "F.Mask" "F.Paste")
			(net "MB0_CM_SENSE_R2_P")
			(options
				(clearance outline)
				(anchor circle)
			)
			(primitives
				(gr_poly
					(pts
						(arc
							(start -0.1778 -0.2794)
							(mid -0.249642 -0.249642)
							(end -0.2794 -0.1778)
						)
						(arc
							(start -0.2794 0.1778)
							(mid -0.249642 0.249642)
							(end -0.1778 0.2794)
						)
						(arc
							(start 0.1778 0.2794)
							(mid 0.249642 0.249642)
							(end 0.2794 0.1778)
						)
						(arc
							(start 0.2794 -0.1778)
							(mid 0.249642 -0.249642)
							(end 0.1778 -0.2794)
						)
					)
					(width 0)
					(fill yes)
				)
			)
		)
		(pad "2" smd custom
			(at 0 0.4445 90)
			(size 0.1397 0.1397)
			(layers "F.Cu" "F.Mask" "F.Paste")
			(net "MB0_CM_SENSE_P")
			(options
				(clearance outline)
				(anchor circle)
			)
			(primitives
				(gr_poly
					(pts
						(arc
							(start -0.1778 -0.2794)
							(mid -0.249642 -0.249642)
							(end -0.2794 -0.1778)
						)
						(arc
							(start -0.2794 0.1778)
							(mid -0.249642 0.249642)
							(end -0.1778 0.2794)
						)
						(arc
							(start 0.1778 0.2794)
							(mid 0.249642 0.249642)
							(end 0.2794 0.1778)
						)
						(arc
							(start 0.2794 -0.1778)
							(mid 0.249642 -0.249642)
							(end 0.1778 -0.2794)
						)
					)
					(width 0)
					(fill yes)
				)
			)
		)
	)
	(footprint ""
		(layer "F.Cu")
		(at 433.324 -142.875 -90)
		(property "Reference" "R568"
			(at 0 0 270)
			(layer "F.SilkS")
			(hide yes)
			(effects
				(font
					(size 1.27 1.27)
				)
			)
		)
		(property "Value" "300KR2F-GP"
			(at 0.064008 -3.993896 270)
			(unlocked yes)
			(layer "F.Fab")
			(hide yes)
			(effects
				(font
					(size 1.016 1.016)
					(thickness 0.1524)
				)
			)
		)
		(property "Device Type" "R402H16"
			(at 0.064008 -5.517896 270)
			(unlocked yes)
			(layer "F.Fab")
			(hide yes)
			(effects
				(font
					(size 1.016 1.016)
					(thickness 0.1524)
				)
			)
		)
		(duplicate_pad_numbers_are_jumpers no)
		(fp_line
			(start -0.508 -0.9398)
			(end -0.508 0.9398)
			(stroke
				(width 0.1524)
				(type default)
			)
			(layer "F.SilkS")
		)
		(fp_line
			(start 0.508 -0.9398)
			(end -0.508 -0.9398)
			(stroke
				(width 0.1524)
				(type default)
			)
			(layer "F.SilkS")
		)
		(fp_rect
			(start -0.508 0.9398)
			(end 0.508 -0.9398)
			(stroke
				(width 0)
				(type default)
			)
			(fill no)
			(layer "F.CrtYd")
		)
		(fp_rect
			(start -0.508 0.9398)
			(end 0.508 -0.9398)
			(stroke
				(width 0)
				(type default)
			)
			(fill no)
			(layer "F.Fab")
		)
		(pad "1" smd custom
			(at 0 -0.4445 270)
			(size 0.1397 0.1397)
			(layers "F.Cu" "F.Mask" "F.Paste")
			(net "SW_HDD_N21")
			(options
				(clearance outline)
				(anchor circle)
			)
			(primitives
				(gr_poly
					(pts
						(arc
							(start -0.1778 -0.2794)
							(mid -0.249642 -0.249642)
							(end -0.2794 -0.1778)
						)
						(arc
							(start -0.2794 0.1778)
							(mid -0.249642 0.249642)
							(end -0.1778 0.2794)
						)
						(arc
							(start 0.1778 0.2794)
							(mid 0.249642 0.249642)
							(end 0.2794 0.1778)
						)
						(arc
							(start 0.2794 -0.1778)
							(mid 0.249642 -0.249642)
							(end 0.1778 -0.2794)
						)
					)
					(width 0)
					(fill yes)
				)
			)
		)
		(pad "2" smd custom
			(at 0 0.4445 270)
			(size 0.1397 0.1397)
			(layers "F.Cu" "F.Mask" "F.Paste")
			(net "P12V_B")
			(options
				(clearance outline)
				(anchor circle)
			)
			(primitives
				(gr_poly
					(pts
						(arc
							(start -0.1778 -0.2794)
							(mid -0.249642 -0.249642)
							(end -0.2794 -0.1778)
						)
						(arc
							(start -0.2794 0.1778)
							(mid -0.249642 0.249642)
							(end -0.1778 0.2794)
						)
						(arc
							(start 0.1778 0.2794)
							(mid 0.249642 0.249642)
							(end 0.2794 0.1778)
						)
						(arc
							(start 0.2794 -0.1778)
							(mid 0.249642 -0.249642)
							(end 0.1778 -0.2794)
						)
					)
					(width 0)
					(fill yes)
				)
			)
		)
	)
	(footprint ""
		(layer "F.Cu")
		(at 241.462306 -139.380214)
		(property "Reference" "R463"
			(at 0 0 0)
			(layer "F.SilkS")
			(hide yes)
			(effects
				(font
					(size 1.27 1.27)
				)
			)
		)
		(property "Value" "0R2J-2-GP"
			(at 0.064008 -3.993896 0)
			(unlocked yes)
			(layer "F.Fab")
			(hide yes)
			(effects
				(font
					(size 1.016 1.016)
					(thickness 0.1524)
				)
			)
		)
		(property "Device Type" "R402H16"
			(at 0.064008 -5.517896 0)
			(unlocked yes)
			(layer "F.Fab")
			(hide yes)
			(effects
				(font
					(size 1.016 1.016)
					(thickness 0.1524)
				)
			)
		)
		(duplicate_pad_numbers_are_jumpers no)
		(fp_line
			(start -0.508 -0.9398)
			(end -0.508 0.9398)
			(stroke
				(width 0.1524)
				(type default)
			)
			(layer "F.SilkS")
		)
		(fp_line
			(start 0.508 -0.9398)
			(end -0.508 -0.9398)
			(stroke
				(width 0.1524)
				(type default)
			)
			(layer "F.SilkS")
		)
		(fp_rect
			(start -0.508 0.9398)
			(end 0.508 -0.9398)
			(stroke
				(width 0)
				(type default)
			)
			(fill no)
			(layer "F.CrtYd")
		)
		(fp_rect
			(start -0.508 0.9398)
			(end 0.508 -0.9398)
			(stroke
				(width 0)
				(type default)
			)
			(fill no)
			(layer "F.Fab")
		)
		(pad "1" smd custom
			(at 0 -0.4445)
			(size 0.1397 0.1397)
			(layers "F.Cu" "F.Mask" "F.Paste")
			(net "I2C_SCC_B_SCL_BUF")
			(options
				(clearance outline)
				(anchor circle)
			)
			(primitives
				(gr_poly
					(pts
						(arc
							(start -0.1778 -0.2794)
							(mid -0.249642 -0.249642)
							(end -0.2794 -0.1778)
						)
						(arc
							(start -0.2794 0.1778)
							(mid -0.249642 0.249642)
							(end -0.1778 0.2794)
						)
						(arc
							(start 0.1778 0.2794)
							(mid 0.249642 0.249642)
							(end 0.2794 0.1778)
						)
						(arc
							(start 0.2794 -0.1778)
							(mid 0.249642 -0.249642)
							(end 0.1778 -0.2794)
						)
					)
					(width 0)
					(fill yes)
				)
			)
		)
		(pad "2" smd custom
			(at 0 0.4445)
			(size 0.1397 0.1397)
			(layers "F.Cu" "F.Mask" "F.Paste")
			(net "I2C_SCC_B_SCL")
			(options
				(clearance outline)
				(anchor circle)
			)
			(primitives
				(gr_poly
					(pts
						(arc
							(start -0.1778 -0.2794)
							(mid -0.249642 -0.249642)
							(end -0.2794 -0.1778)
						)
						(arc
							(start -0.2794 0.1778)
							(mid -0.249642 0.249642)
							(end -0.1778 0.2794)
						)
						(arc
							(start 0.1778 0.2794)
							(mid 0.249642 0.249642)
							(end 0.2794 0.1778)
						)
						(arc
							(start 0.2794 -0.1778)
							(mid 0.249642 -0.249642)
							(end 0.1778 -0.2794)
						)
					)
					(width 0)
					(fill yes)
				)
			)
		)
	)
)
